(kicad_pcb
	(version 20260206)
	(generator "pcbnew")
	(generator_version "10.0")
	(general
		(thickness 1.6)
		(legacy_teardrops no)
	)
	(paper "A4")
	(title_block
		(title "v1-chassis-manager — T6M_CM_d_v01_1031_1645.brd")
		(comment 1 "Open CloudServer (Microsoft) / footprints 1318-1327 of 2512")
	)
	(layers
		(0 "F.Cu" signal "TOP")
		(4 "In1.Cu" signal "GND1")
		(6 "In2.Cu" signal "IN1")
		(8 "In3.Cu" signal "VCC1")
		(10 "In4.Cu" signal "VCC2")
		(12 "In5.Cu" signal "GND2")
		(14 "In6.Cu" signal "IN2")
		(16 "In7.Cu" signal "IN3")
		(18 "In8.Cu" signal "GND3")
		(2 "B.Cu" signal "BOTTOM")
		(9 "F.Adhes" user "F.Adhesive")
		(11 "B.Adhes" user "B.Adhesive")
		(13 "F.Paste" user "Package Geometry/Pastemask Top")
		(15 "B.Paste" user "Package Geometry/Pastemask Bottom")
		(5 "F.SilkS" user "Ref Des/Silkscreen Top")
		(7 "B.SilkS" user "Ref Des/Silkscreen Bottom")
		(1 "F.Mask" user "Board Geometry/Soldermask Top")
		(3 "B.Mask" user "Board Geometry/Soldermask Bottom")
		(17 "Dwgs.User" user "User.Drawings")
		(19 "Cmts.User" user "User.Comments")
		(21 "Eco1.User" user "User.Eco1")
		(23 "Eco2.User" user "User.Eco2")
		(25 "Edge.Cuts" user "Board Geometry/Outline")
		(27 "Margin" user)
		(31 "F.CrtYd" user "Package Geometry/Place Bound Top")
		(29 "B.CrtYd" user "Package Geometry/Place Bound Bottom")
		(35 "F.Fab" user "Ref Des/Assembly Top")
		(33 "B.Fab" user "Ref Des/Assembly Bottom")
	)
	(footprint ""
		(layer "F.Cu")
		(at 116.074952 -123.297442 90)
		(property "Reference" "PC94"
			(at -0.530352 4.81457 90)
			(unlocked yes)
			(layer "F.SilkS")
			(effects
				(font
					(size 0.7874 0.5842)
					(thickness 0.1524)
				)
				(justify left)
			)
		)
		(property "Value" ""
			(at 0 0 90)
			(layer "F.Fab")
			(effects
				(font
					(size 1.27 1.27)
				)
			)
		)
		(duplicate_pad_numbers_are_jumpers no)
		(fp_line
			(start 2.2098 -0.9398)
			(end 2.2098 0.9398)
			(stroke
				(width 0.1524)
				(type default)
			)
			(layer "F.SilkS")
		)
		(fp_line
			(start 0 -0.9398)
			(end 0 0.9398)
			(stroke
				(width 0.1524)
				(type default)
			)
			(layer "F.SilkS")
		)
		(fp_line
			(start -2.2098 -0.9398)
			(end 2.2098 -0.9398)
			(stroke
				(width 0.1524)
				(type default)
			)
			(layer "F.SilkS")
		)
		(fp_line
			(start 2.2098 0.9398)
			(end -2.2098 0.9398)
			(stroke
				(width 0.1524)
				(type default)
			)
			(layer "F.SilkS")
		)
		(fp_line
			(start -2.2098 0.9398)
			(end -2.2098 -0.9398)
			(stroke
				(width 0.1524)
				(type default)
			)
			(layer "F.SilkS")
		)
		(fp_poly
			(pts
				(xy -1.6764 0.889) (xy -1.6764 0.7874) (xy -2.0574 0.7874) (xy -2.0574 -0.7874) (xy -1.6764 -0.7874)
				(xy -1.6764 -0.9398) (xy 1.6764 -0.9398) (xy 1.6764 -0.7874) (xy 2.0574 -0.7874) (xy 2.0574 0.7874)
				(xy 1.6764 0.7874) (xy 1.6764 0.9398) (xy -1.6764 0.9398)
			)
			(stroke
				(width 0)
				(type default)
			)
			(fill no)
			(layer "F.CrtYd")
		)
		(fp_line
			(start 1.700022 -0.899922)
			(end 1.700022 0.899922)
			(stroke
				(width 0.1)
				(type default)
			)
			(layer "F.Fab")
		)
		(fp_line
			(start -1.700022 -0.899922)
			(end 1.700022 -0.899922)
			(stroke
				(width 0.1)
				(type default)
			)
			(layer "F.Fab")
		)
		(fp_line
			(start 1.700022 0.899922)
			(end -1.700022 0.899922)
			(stroke
				(width 0.1)
				(type default)
			)
			(layer "F.Fab")
		)
		(fp_line
			(start -1.700022 0.899922)
			(end -1.700022 -0.899922)
			(stroke
				(width 0.1)
				(type default)
			)
			(layer "F.Fab")
		)
		(pad "1" smd rect
			(at 1.4732 0 90)
			(size 1.1684 1.5748)
			(layers "F.Cu" "F.Mask" "F.Paste")
			(net "SW_VR_PVCCP_NODE1_VIN_FLT")
		)
		(pad "2" smd rect
			(at -1.4732 0 90)
			(size 1.1684 1.5748)
			(layers "F.Cu" "F.Mask" "F.Paste")
			(net "GND")
		)
	)
	(footprint ""
		(layer "F.Cu")
		(at 127.517652 -133.17855 -90)
		(property "Reference" "R280"
			(at 3.941572 -0.084328 90)
			(unlocked yes)
			(layer "F.SilkS")
			(effects
				(font
					(size 0.7874 0.5842)
					(thickness 0.1524)
				)
				(justify left)
			)
		)
		(property "Value" ""
			(at 0 0 270)
			(layer "F.Fab")
			(effects
				(font
					(size 1.27 1.27)
				)
			)
		)
		(duplicate_pad_numbers_are_jumpers no)
		(fp_line
			(start -0.7874 0.4064)
			(end -0.7874 -0.4064)
			(stroke
				(width 0.1524)
				(type default)
			)
			(layer "F.SilkS")
		)
		(fp_line
			(start 0.7874 0.4064)
			(end -0.7874 0.4064)
			(stroke
				(width 0.1524)
				(type default)
			)
			(layer "F.SilkS")
		)
		(fp_line
			(start -0.7874 -0.4064)
			(end 0.7874 -0.4064)
			(stroke
				(width 0.1524)
				(type default)
			)
			(layer "F.SilkS")
		)
		(fp_line
			(start 0.7874 -0.4064)
			(end 0.7874 0.4064)
			(stroke
				(width 0.1524)
				(type default)
			)
			(layer "F.SilkS")
		)
		(fp_poly
			(pts
				(xy -0.508 0.2794) (xy -0.508 0.2286) (xy -0.635 0.2286) (xy -0.635 -0.254) (xy -0.5334 -0.254)
				(xy -0.5334 -0.2794) (xy 0.5334 -0.2794) (xy 0.5334 -0.254) (xy 0.635 -0.254) (xy 0.635 0.254) (xy 0.5334 0.254)
				(xy 0.5334 0.2794)
			)
			(stroke
				(width 0)
				(type default)
			)
			(fill no)
			(layer "F.CrtYd")
		)
		(pad "1" smd rect
			(at 0.40005 0 270)
			(size 0.4572 0.508)
			(layers "F.Cu" "F.Mask" "F.Paste")
			(net "P3V3_NODE1")
		)
		(pad "2" smd rect
			(at -0.40005 0 270)
			(size 0.4572 0.508)
			(layers "F.Cu" "F.Mask" "F.Paste")
			(net "PE_SW_USB_PERST_L")
		)
	)
	(footprint ""
		(layer "F.Cu")
		(at 64.24676 -185.205624 90)
		(property "Reference" "C694"
			(at 4.006088 -0.795528 90)
			(unlocked yes)
			(layer "F.SilkS")
			(effects
				(font
					(size 0.7874 0.5842)
					(thickness 0.1524)
				)
				(justify left)
			)
		)
		(property "Value" ""
			(at 0 0 90)
			(layer "F.Fab")
			(effects
				(font
					(size 1.27 1.27)
				)
			)
		)
		(duplicate_pad_numbers_are_jumpers no)
		(fp_line
			(start 0.7874 -0.4064)
			(end 0.7874 0.4064)
			(stroke
				(width 0.1524)
				(type default)
			)
			(layer "F.SilkS")
		)
		(fp_line
			(start -0.7874 -0.4064)
			(end 0.7874 -0.4064)
			(stroke
				(width 0.1524)
				(type default)
			)
			(layer "F.SilkS")
		)
		(fp_line
			(start 0 0.381)
			(end 0 -0.381)
			(stroke
				(width 0.1524)
				(type default)
			)
			(layer "F.SilkS")
		)
		(fp_line
			(start 0.7874 0.4064)
			(end -0.7874 0.4064)
			(stroke
				(width 0.1524)
				(type default)
			)
			(layer "F.SilkS")
		)
		(fp_line
			(start -0.7874 0.4064)
			(end -0.7874 -0.4064)
			(stroke
				(width 0.1524)
				(type default)
			)
			(layer "F.SilkS")
		)
		(fp_poly
			(pts
				(xy -0.5334 0.254) (xy -0.635 0.254) (xy -0.635 0.2286) (xy -0.635 -0.254) (xy -0.5334 -0.254) (xy -0.5334 -0.2794)
				(xy 0.5334 -0.2794) (xy 0.5334 -0.254) (xy 0.635 -0.254) (xy 0.635 0.254) (xy 0.5334 0.254) (xy 0.5334 0.2794)
				(xy -0.508 0.2794) (xy -0.5334 0.2794)
			)
			(stroke
				(width 0)
				(type default)
			)
			(fill no)
			(layer "F.CrtYd")
		)
		(pad "1" smd rect
			(at 0.40005 0 90)
			(size 0.4572 0.508)
			(layers "F.Cu" "F.Mask" "F.Paste")
			(net "UART_T2_NODE1_RXD")
		)
		(pad "2" smd rect
			(at -0.40005 0 90)
			(size 0.4572 0.508)
			(layers "F.Cu" "F.Mask" "F.Paste")
			(net "GND")
		)
	)
	(footprint ""
		(layer "F.Cu")
		(at 112.76076 -188.126624 90)
		(property "Reference" "C763"
			(at 5.151882 -0.377698 90)
			(unlocked yes)
			(layer "F.SilkS")
			(effects
				(font
					(size 0.7874 0.5842)
					(thickness 0.1524)
				)
				(justify left)
			)
		)
		(property "Value" ""
			(at 0 0 90)
			(layer "F.Fab")
			(effects
				(font
					(size 1.27 1.27)
				)
			)
		)
		(duplicate_pad_numbers_are_jumpers no)
		(fp_line
			(start 0.7874 -0.4064)
			(end 0.7874 0.4064)
			(stroke
				(width 0.1524)
				(type default)
			)
			(layer "F.SilkS")
		)
		(fp_line
			(start -0.7874 -0.4064)
			(end 0.7874 -0.4064)
			(stroke
				(width 0.1524)
				(type default)
			)
			(layer "F.SilkS")
		)
		(fp_line
			(start 0 0.381)
			(end 0 -0.381)
			(stroke
				(width 0.1524)
				(type default)
			)
			(layer "F.SilkS")
		)
		(fp_line
			(start 0.7874 0.4064)
			(end -0.7874 0.4064)
			(stroke
				(width 0.1524)
				(type default)
			)
			(layer "F.SilkS")
		)
		(fp_line
			(start -0.7874 0.4064)
			(end -0.7874 -0.4064)
			(stroke
				(width 0.1524)
				(type default)
			)
			(layer "F.SilkS")
		)
		(fp_poly
			(pts
				(xy -0.5334 0.254) (xy -0.635 0.254) (xy -0.635 0.2286) (xy -0.635 -0.254) (xy -0.5334 -0.254) (xy -0.5334 -0.2794)
				(xy 0.5334 -0.2794) (xy 0.5334 -0.254) (xy 0.635 -0.254) (xy 0.635 0.254) (xy 0.5334 0.254) (xy 0.5334 0.2794)
				(xy -0.508 0.2794) (xy -0.5334 0.2794)
			)
			(stroke
				(width 0)
				(type default)
			)
			(fill no)
			(layer "F.CrtYd")
		)
		(pad "1" smd rect
			(at 0.40005 0 90)
			(size 0.4572 0.508)
			(layers "F.Cu" "F.Mask" "F.Paste")
			(net "UART_T8_NODE4_TXD_R")
		)
		(pad "2" smd rect
			(at -0.40005 0 90)
			(size 0.4572 0.508)
			(layers "F.Cu" "F.Mask" "F.Paste")
			(net "GND")
		)
	)
	(footprint ""
		(layer "F.Cu")
		(at 160.008062 -98.343212 180)
		(property "Reference" "R533"
			(at 3.956304 -0.569468 0)
			(unlocked yes)
			(layer "F.SilkS")
			(effects
				(font
					(size 0.7874 0.5842)
					(thickness 0.1524)
				)
				(justify left)
			)
		)
		(property "Value" ""
			(at 0 0 180)
			(layer "F.Fab")
			(effects
				(font
					(size 1.27 1.27)
				)
			)
		)
		(duplicate_pad_numbers_are_jumpers no)
		(fp_line
			(start 0.7874 0.4064)
			(end -0.7874 0.4064)
			(stroke
				(width 0.1524)
				(type default)
			)
			(layer "F.SilkS")
		)
		(fp_line
			(start 0.7874 -0.4064)
			(end 0.7874 0.4064)
			(stroke
				(width 0.1524)
				(type default)
			)
			(layer "F.SilkS")
		)
		(fp_line
			(start -0.7874 0.4064)
			(end -0.7874 -0.4064)
			(stroke
				(width 0.1524)
				(type default)
			)
			(layer "F.SilkS")
		)
		(fp_line
			(start -0.7874 -0.4064)
			(end 0.7874 -0.4064)
			(stroke
				(width 0.1524)
				(type default)
			)
			(layer "F.SilkS")
		)
		(fp_poly
			(pts
				(xy -0.508 0.2794) (xy -0.508 0.2286) (xy -0.635 0.2286) (xy -0.635 -0.254) (xy -0.5334 -0.254)
				(xy -0.5334 -0.2794) (xy 0.5334 -0.2794) (xy 0.5334 -0.254) (xy 0.635 -0.254) (xy 0.635 0.254) (xy 0.5334 0.254)
				(xy 0.5334 0.2794)
			)
			(stroke
				(width 0)
				(type default)
			)
			(fill no)
			(layer "F.CrtYd")
		)
		(pad "1" smd rect
			(at 0.40005 0 180)
			(size 0.4572 0.508)
			(layers "F.Cu" "F.Mask" "F.Paste")
			(net "P3V3_NODE1")
		)
		(pad "2" smd rect
			(at -0.40005 0 180)
			(size 0.4572 0.508)
			(layers "F.Cu" "F.Mask" "F.Paste")
			(net "USB_NODE1_PECREQ_L")
		)
	)
	(footprint ""
		(layer "F.Cu")
		(at 44.207176 -180.333904 180)
		(property "Reference" "C775"
			(at 0.986028 -132.587492 0)
			(unlocked yes)
			(layer "F.SilkS")
			(effects
				(font
					(size 0.7874 0.5842)
					(thickness 0.1524)
				)
				(justify left)
			)
		)
		(property "Value" ""
			(at 0 0 180)
			(layer "F.Fab")
			(effects
				(font
					(size 1.27 1.27)
				)
			)
		)
		(duplicate_pad_numbers_are_jumpers no)
		(fp_line
			(start 0.7874 0.4064)
			(end -0.7874 0.4064)
			(stroke
				(width 0.1524)
				(type default)
			)
			(layer "F.SilkS")
		)
		(fp_line
			(start 0.7874 -0.4064)
			(end 0.7874 0.4064)
			(stroke
				(width 0.1524)
				(type default)
			)
			(layer "F.SilkS")
		)
		(fp_line
			(start 0 0.381)
			(end 0 -0.381)
			(stroke
				(width 0.1524)
				(type default)
			)
			(layer "F.SilkS")
		)
		(fp_line
			(start -0.7874 0.4064)
			(end -0.7874 -0.4064)
			(stroke
				(width 0.1524)
				(type default)
			)
			(layer "F.SilkS")
		)
		(fp_line
			(start -0.7874 -0.4064)
			(end 0.7874 -0.4064)
			(stroke
				(width 0.1524)
				(type default)
			)
			(layer "F.SilkS")
		)
		(fp_poly
			(pts
				(xy -0.5334 0.254) (xy -0.635 0.254) (xy -0.635 0.2286) (xy -0.635 -0.254) (xy -0.5334 -0.254) (xy -0.5334 -0.2794)
				(xy 0.5334 -0.2794) (xy 0.5334 -0.254) (xy 0.635 -0.254) (xy 0.635 0.254) (xy 0.5334 0.254) (xy 0.5334 0.2794)
				(xy -0.508 0.2794) (xy -0.5334 0.2794)
			)
			(stroke
				(width 0)
				(type default)
			)
			(fill no)
			(layer "F.CrtYd")
		)
		(pad "1" smd rect
			(at 0.40005 0 180)
			(size 0.4572 0.508)
			(layers "F.Cu" "F.Mask" "F.Paste")
			(net "P12V_AUX")
		)
		(pad "2" smd rect
			(at -0.40005 0 180)
			(size 0.4572 0.508)
			(layers "F.Cu" "F.Mask" "F.Paste")
			(net "GND")
		)
	)
	(footprint ""
		(layer "F.Cu")
		(at 159.545782 -106.368596 180)
		(property "Reference" "R525"
			(at 1.36779 1.011682 0)
			(unlocked yes)
			(layer "F.SilkS")
			(effects
				(font
					(size 0.7874 0.5842)
					(thickness 0.1524)
				)
				(justify left)
			)
		)
		(property "Value" ""
			(at 0 0 180)
			(layer "F.Fab")
			(effects
				(font
					(size 1.27 1.27)
				)
			)
		)
		(duplicate_pad_numbers_are_jumpers no)
		(fp_line
			(start 0.7874 0.4064)
			(end -0.7874 0.4064)
			(stroke
				(width 0.1524)
				(type default)
			)
			(layer "F.SilkS")
		)
		(fp_line
			(start 0.7874 -0.4064)
			(end 0.7874 0.4064)
			(stroke
				(width 0.1524)
				(type default)
			)
			(layer "F.SilkS")
		)
		(fp_line
			(start -0.7874 0.4064)
			(end -0.7874 -0.4064)
			(stroke
				(width 0.1524)
				(type default)
			)
			(layer "F.SilkS")
		)
		(fp_line
			(start -0.7874 -0.4064)
			(end 0.7874 -0.4064)
			(stroke
				(width 0.1524)
				(type default)
			)
			(layer "F.SilkS")
		)
		(fp_poly
			(pts
				(xy -0.508 0.2794) (xy -0.508 0.2286) (xy -0.635 0.2286) (xy -0.635 -0.254) (xy -0.5334 -0.254)
				(xy -0.5334 -0.2794) (xy 0.5334 -0.2794) (xy 0.5334 -0.254) (xy 0.635 -0.254) (xy 0.635 0.254) (xy 0.5334 0.254)
				(xy 0.5334 0.2794)
			)
			(stroke
				(width 0)
				(type default)
			)
			(fill no)
			(layer "F.CrtYd")
		)
		(pad "1" smd rect
			(at 0.40005 0 180)
			(size 0.4572 0.508)
			(layers "F.Cu" "F.Mask" "F.Paste")
			(net "P3V3_NODE1")
		)
		(pad "2" smd rect
			(at -0.40005 0 180)
			(size 0.4572 0.508)
			(layers "F.Cu" "F.Mask" "F.Paste")
			(net "USB_NODE1_SMI_L")
		)
	)
	(footprint ""
		(layer "F.Cu")
		(at 66.46799 -6.332728)
		(property "Reference" "PC51"
			(at -1.426718 -4.301744 0)
			(unlocked yes)
			(layer "F.SilkS")
			(effects
				(font
					(size 0.7874 0.5842)
					(thickness 0.1524)
				)
				(justify left)
			)
		)
		(property "Value" ""
			(at 0 0 0)
			(layer "F.Fab")
			(effects
				(font
					(size 1.27 1.27)
				)
			)
		)
		(duplicate_pad_numbers_are_jumpers no)
		(fp_line
			(start -0.7874 -0.4064)
			(end 0.7874 -0.4064)
			(stroke
				(width 0.1524)
				(type default)
			)
			(layer "F.SilkS")
		)
		(fp_line
			(start -0.7874 0.4064)
			(end -0.7874 -0.4064)
			(stroke
				(width 0.1524)
				(type default)
			)
			(layer "F.SilkS")
		)
		(fp_line
			(start 0 0.381)
			(end 0 -0.381)
			(stroke
				(width 0.1524)
				(type default)
			)
			(layer "F.SilkS")
		)
		(fp_line
			(start 0.7874 -0.4064)
			(end 0.7874 0.4064)
			(stroke
				(width 0.1524)
				(type default)
			)
			(layer "F.SilkS")
		)
		(fp_line
			(start 0.7874 0.4064)
			(end -0.7874 0.4064)
			(stroke
				(width 0.1524)
				(type default)
			)
			(layer "F.SilkS")
		)
		(fp_poly
			(pts
				(xy -0.5334 0.254) (xy -0.635 0.254) (xy -0.635 0.2286) (xy -0.635 -0.254) (xy -0.5334 -0.254) (xy -0.5334 -0.2794)
				(xy 0.5334 -0.2794) (xy 0.5334 -0.254) (xy 0.635 -0.254) (xy 0.635 0.254) (xy 0.5334 0.254) (xy 0.5334 0.2794)
				(xy -0.508 0.2794) (xy -0.5334 0.2794)
			)
			(stroke
				(width 0)
				(type default)
			)
			(fill no)
			(layer "F.CrtYd")
		)
		(pad "1" smd rect
			(at 0.40005 0)
			(size 0.4572 0.508)
			(layers "F.Cu" "F.Mask" "F.Paste")
			(net "P3V3_NODE1_VREG5")
		)
		(pad "2" smd rect
			(at -0.40005 0)
			(size 0.4572 0.508)
			(layers "F.Cu" "F.Mask" "F.Paste")
			(net "GND")
		)
	)
	(footprint ""
		(layer "F.Cu")
		(at 152.755854 -135.155432 180)
		(property "Reference" "C801"
			(at 5.190236 -1.942084 0)
			(unlocked yes)
			(layer "F.SilkS")
			(effects
				(font
					(size 0.7874 0.5842)
					(thickness 0.1524)
				)
				(justify left)
			)
		)
		(property "Value" ""
			(at 0 0 180)
			(layer "F.Fab")
			(effects
				(font
					(size 1.27 1.27)
				)
			)
		)
		(duplicate_pad_numbers_are_jumpers no)
		(fp_line
			(start 0.7874 0.4064)
			(end -0.7874 0.4064)
			(stroke
				(width 0.1524)
				(type default)
			)
			(layer "F.SilkS")
		)
		(fp_line
			(start 0.7874 -0.4064)
			(end 0.7874 0.4064)
			(stroke
				(width 0.1524)
				(type default)
			)
			(layer "F.SilkS")
		)
		(fp_line
			(start 0 0.381)
			(end 0 -0.381)
			(stroke
				(width 0.1524)
				(type default)
			)
			(layer "F.SilkS")
		)
		(fp_line
			(start -0.7874 0.4064)
			(end -0.7874 -0.4064)
			(stroke
				(width 0.1524)
				(type default)
			)
			(layer "F.SilkS")
		)
		(fp_line
			(start -0.7874 -0.4064)
			(end 0.7874 -0.4064)
			(stroke
				(width 0.1524)
				(type default)
			)
			(layer "F.SilkS")
		)
		(fp_poly
			(pts
				(xy -0.5334 0.254) (xy -0.635 0.254) (xy -0.635 0.2286) (xy -0.635 -0.254) (xy -0.5334 -0.254) (xy -0.5334 -0.2794)
				(xy 0.5334 -0.2794) (xy 0.5334 -0.254) (xy 0.635 -0.254) (xy 0.635 0.254) (xy 0.5334 0.254) (xy 0.5334 0.2794)
				(xy -0.508 0.2794) (xy -0.5334 0.2794)
			)
			(stroke
				(width 0)
				(type default)
			)
			(fill no)
			(layer "F.CrtYd")
		)
		(pad "1" smd rect
			(at 0.40005 0 180)
			(size 0.4572 0.508)
			(layers "F.Cu" "F.Mask" "F.Paste")
			(net "GND")
		)
		(pad "2" smd rect
			(at -0.40005 0 180)
			(size 0.4572 0.508)
			(layers "F.Cu" "F.Mask" "F.Paste")
			(net "RST_BTN_L")
		)
	)
	(footprint ""
		(layer "F.Cu")
		(at 44.702222 -106.475784 90)
		(property "Reference" "PR6"
			(at -2.327148 -3.184144 90)
			(unlocked yes)
			(layer "F.SilkS")
			(effects
				(font
					(size 0.7874 0.5842)
					(thickness 0.1524)
				)
				(justify left)
			)
		)
		(property "Value" ""
			(at 0 0 90)
			(layer "F.Fab")
			(effects
				(font
					(size 1.27 1.27)
				)
			)
		)
		(duplicate_pad_numbers_are_jumpers no)
		(fp_line
			(start 0.7874 -0.4064)
			(end 0.7874 0.4064)
			(stroke
				(width 0.1524)
				(type default)
			)
			(layer "F.SilkS")
		)
		(fp_line
			(start -0.7874 -0.4064)
			(end 0.7874 -0.4064)
			(stroke
				(width 0.1524)
				(type default)
			)
			(layer "F.SilkS")
		)
		(fp_line
			(start 0.7874 0.4064)
			(end -0.7874 0.4064)
			(stroke
				(width 0.1524)
				(type default)
			)
			(layer "F.SilkS")
		)
		(fp_line
			(start -0.7874 0.4064)
			(end -0.7874 -0.4064)
			(stroke
				(width 0.1524)
				(type default)
			)
			(layer "F.SilkS")
		)
		(fp_poly
			(pts
				(xy -0.508 0.2794) (xy -0.508 0.2286) (xy -0.635 0.2286) (xy -0.635 -0.254) (xy -0.5334 -0.254)
				(xy -0.5334 -0.2794) (xy 0.5334 -0.2794) (xy 0.5334 -0.254) (xy 0.635 -0.254) (xy 0.635 0.254) (xy 0.5334 0.254)
				(xy 0.5334 0.2794)
			)
			(stroke
				(width 0)
				(type default)
			)
			(fill no)
			(layer "F.CrtYd")
		)
		(pad "1" smd rect
			(at 0.40005 0 90)
			(size 0.4572 0.508)
			(layers "F.Cu" "F.Mask" "F.Paste")
			(net "PWRGD_NODE1_P3V3_STB_PG")
		)
		(pad "2" smd rect
			(at -0.40005 0 90)
			(size 0.4572 0.508)
			(layers "F.Cu" "F.Mask" "F.Paste")
			(net "GND")
		)
	)
)
